# S9S_MB_2U (Grand Teton) — schematic netlist excerpt (pin names and nets, part order shuffled) for the footprints in the layout excerpt that follows; sources: Cadence DE-HDL packaged netlist, KiCad conversion of 03242023_DA0F0TMBIJ0_F0T_Motherboard_J_brd_V01_OCP.brd

C1397  Q_CAP  47UF 4V 20% X6S  pkg C0805  page 75 : A = PVPP_HBM_CPU0 ; B = GND
R819  Q_RES  1K 1% CHIP  pkg 0402LF  page 130 : A = PVCCD_HV_CPU1 ; B = RST_M_GH_CPU1_FPGA_N
R900  Q_RES  33.2 1% CHIP  pkg 0402LF  page 114 : A = PWRGD_CHD_CPU1_DIMM2 ; B = PWRGD_FAIL_CPU1_CD

(kicad_pcb
	(version 20260206)
	(generator "pcbnew")
	(generator_version "10.0")
	(general
		(thickness 1.6)
		(legacy_teardrops no)
	)
	(paper "A4")
	(title_block
		(title "03242023_DA0F0TMBIJ0_F0T_Motherboard_J_brd_V01_OCP.brd")
		(comment 1 "Grand Teton / footprints 5422-5424 of 6105")
	)
	(layers
		(0 "F.Cu" signal "TOP")
		(4 "In1.Cu" signal "GND")
		(6 "In2.Cu" signal "IN1")
		(8 "In3.Cu" signal "GND1")
		(10 "In4.Cu" signal "IN2")
		(12 "In5.Cu" signal "GND2")
		(14 "In6.Cu" signal "IN3")
		(16 "In7.Cu" signal "GND3")
		(18 "In8.Cu" signal "VCC")
		(20 "In9.Cu" signal "VCC1")
		(22 "In10.Cu" signal "GND4")
		(24 "In11.Cu" signal "IN4")
		(26 "In12.Cu" signal "GND5")
		(28 "In13.Cu" signal "IN5")
		(30 "In14.Cu" signal "GND6")
		(32 "In15.Cu" signal "IN6")
		(34 "In16.Cu" signal "GND7")
		(2 "B.Cu" signal "BOTTOM")
		(9 "F.Adhes" user "F.Adhesive")
		(11 "B.Adhes" user "B.Adhesive")
		(13 "F.Paste" user "Package Geometry/Pastemask Top")
		(15 "B.Paste" user "Package Geometry/Pastemask Bottom")
		(5 "F.SilkS" user "Ref Des/Silkscreen Top")
		(7 "B.SilkS" user "Ref Des/Silkscreen Bottom")
		(1 "F.Mask" user "Board Geometry/Soldermask Top")
		(3 "B.Mask" user "Board Geometry/Soldermask Bottom")
		(17 "Dwgs.User" user "User.Drawings")
		(19 "Cmts.User" user "User.Comments")
		(21 "Eco1.User" user "User.Eco1")
		(23 "Eco2.User" user "User.Eco2")
		(25 "Edge.Cuts" user "Board Geometry/Outline")
		(27 "Margin" user)
		(31 "F.CrtYd" user "Package Geometry/Place Bound Top")
		(29 "B.CrtYd" user "Package Geometry/Place Bound Bottom")
		(35 "F.Fab" user "Ref Des/Assembly Top")
		(33 "B.Fab" user "Ref Des/Assembly Bottom")
	)
	(footprint ""
		(layer "B.Cu")
		(at 19.760946 -319.268856 180)
		(property "Reference" "R900"
			(at 0 0 0)
			(layer "B.SilkS")
			(hide yes)
			(effects
				(font
					(size 1.27 1.27)
				)
				(justify mirror)
			)
		)
		(property "Value" ""
			(at 0 0 0)
			(layer "B.Fab")
			(effects
				(font
					(size 1.27 1.27)
				)
				(justify mirror)
			)
		)
		(duplicate_pad_numbers_are_jumpers no)
		(fp_line
			(start 0.7874 0.4064)
			(end 0.7874 -0.4064)
			(stroke
				(width 0.1524)
				(type default)
			)
			(layer "B.SilkS")
		)
		(fp_line
			(start 0.7874 -0.4064)
			(end -0.7874 -0.4064)
			(stroke
				(width 0.1524)
				(type default)
			)
			(layer "B.SilkS")
		)
		(fp_line
			(start -0.7874 0.4064)
			(end 0.7874 0.4064)
			(stroke
				(width 0.1524)
				(type default)
			)
			(layer "B.SilkS")
		)
		(fp_line
			(start -0.7874 -0.4064)
			(end -0.7874 0.4064)
			(stroke
				(width 0.1524)
				(type default)
			)
			(layer "B.SilkS")
		)
		(fp_line
			(start 0.67945 0.3048)
			(end 0.67945 -0.305054)
			(stroke
				(width 0.1)
				(type default)
			)
			(layer "B.Fab")
		)
		(fp_line
			(start 0.67945 -0.305054)
			(end 0.12065 -0.305054)
			(stroke
				(width 0.1)
				(type default)
			)
			(layer "B.Fab")
		)
		(fp_line
			(start 0.12065 0.3048)
			(end 0.67945 0.3048)
			(stroke
				(width 0.1)
				(type default)
			)
			(layer "B.Fab")
		)
		(fp_line
			(start 0.12065 0.2794)
			(end 0.12065 0.3048)
			(stroke
				(width 0.1)
				(type default)
			)
			(layer "B.Fab")
		)
		(fp_line
			(start 0.12065 -0.2794)
			(end -0.12065 -0.2794)
			(stroke
				(width 0.1)
				(type default)
			)
			(layer "B.Fab")
		)
		(fp_line
			(start 0.12065 -0.305054)
			(end 0.12065 -0.2794)
			(stroke
				(width 0.1)
				(type default)
			)
			(layer "B.Fab")
		)
		(fp_line
			(start -0.120396 0.3048)
			(end -0.120396 0.2794)
			(stroke
				(width 0.1)
				(type default)
			)
			(layer "B.Fab")
		)
		(fp_line
			(start -0.120396 0.2794)
			(end 0.12065 0.2794)
			(stroke
				(width 0.1)
				(type default)
			)
			(layer "B.Fab")
		)
		(fp_line
			(start -0.12065 -0.2794)
			(end -0.12065 -0.3048)
			(stroke
				(width 0.1)
				(type default)
			)
			(layer "B.Fab")
		)
		(fp_line
			(start -0.12065 -0.3048)
			(end -0.67945 -0.3048)
			(stroke
				(width 0.1)
				(type default)
			)
			(layer "B.Fab")
		)
		(fp_line
			(start -0.67945 0.3048)
			(end -0.120396 0.3048)
			(stroke
				(width 0.1)
				(type default)
			)
			(layer "B.Fab")
		)
		(fp_line
			(start -0.67945 -0.3048)
			(end -0.67945 0.3048)
			(stroke
				(width 0.1)
				(type default)
			)
			(layer "B.Fab")
		)
		(pad "1" smd circle
			(at 0.40005 0)
			(size 0 0)
			(layers "B.Cu" "B.Mask" "B.Paste")
			(net "PWRGD_CHD_CPU1_DIMM2")
		)
		(pad "2" smd circle
			(at -0.40005 0)
			(size 0 0)
			(layers "B.Cu" "B.Mask" "B.Paste")
			(net "PWRGD_FAIL_CPU1_CD")
		)
	)
	(footprint ""
		(layer "B.Cu")
		(at 189.232286 -193.615056 -90)
		(property "Reference" "R819"
			(at 0 0 90)
			(layer "B.SilkS")
			(hide yes)
			(effects
				(font
					(size 1.27 1.27)
				)
				(justify mirror)
			)
		)
		(property "Value" ""
			(at 0 0 90)
			(layer "B.Fab")
			(effects
				(font
					(size 1.27 1.27)
				)
				(justify mirror)
			)
		)
		(duplicate_pad_numbers_are_jumpers no)
		(fp_line
			(start -0.7874 0.4064)
			(end 0.7874 0.4064)
			(stroke
				(width 0.1524)
				(type default)
			)
			(layer "B.SilkS")
		)
		(fp_line
			(start 0.7874 0.4064)
			(end 0.7874 -0.4064)
			(stroke
				(width 0.1524)
				(type default)
			)
			(layer "B.SilkS")
		)
		(fp_line
			(start -0.7874 -0.4064)
			(end -0.7874 0.4064)
			(stroke
				(width 0.1524)
				(type default)
			)
			(layer "B.SilkS")
		)
		(fp_line
			(start 0.7874 -0.4064)
			(end -0.7874 -0.4064)
			(stroke
				(width 0.1524)
				(type default)
			)
			(layer "B.SilkS")
		)
		(fp_line
			(start -0.67945 0.3048)
			(end -0.120396 0.3048)
			(stroke
				(width 0.1)
				(type default)
			)
			(layer "B.Fab")
		)
		(fp_line
			(start -0.120396 0.3048)
			(end -0.120396 0.2794)
			(stroke
				(width 0.1)
				(type default)
			)
			(layer "B.Fab")
		)
		(fp_line
			(start 0.12065 0.3048)
			(end 0.67945 0.3048)
			(stroke
				(width 0.1)
				(type default)
			)
			(layer "B.Fab")
		)
		(fp_line
			(start 0.67945 0.3048)
			(end 0.67945 -0.305054)
			(stroke
				(width 0.1)
				(type default)
			)
			(layer "B.Fab")
		)
		(fp_line
			(start -0.120396 0.2794)
			(end 0.12065 0.2794)
			(stroke
				(width 0.1)
				(type default)
			)
			(layer "B.Fab")
		)
		(fp_line
			(start 0.12065 0.2794)
			(end 0.12065 0.3048)
			(stroke
				(width 0.1)
				(type default)
			)
			(layer "B.Fab")
		)
		(fp_line
			(start -0.12065 -0.2794)
			(end -0.12065 -0.3048)
			(stroke
				(width 0.1)
				(type default)
			)
			(layer "B.Fab")
		)
		(fp_line
			(start 0.12065 -0.2794)
			(end -0.12065 -0.2794)
			(stroke
				(width 0.1)
				(type default)
			)
			(layer "B.Fab")
		)
		(fp_line
			(start -0.67945 -0.3048)
			(end -0.67945 0.3048)
			(stroke
				(width 0.1)
				(type default)
			)
			(layer "B.Fab")
		)
		(fp_line
			(start -0.12065 -0.3048)
			(end -0.67945 -0.3048)
			(stroke
				(width 0.1)
				(type default)
			)
			(layer "B.Fab")
		)
		(fp_line
			(start 0.12065 -0.305054)
			(end 0.12065 -0.2794)
			(stroke
				(width 0.1)
				(type default)
			)
			(layer "B.Fab")
		)
		(fp_line
			(start 0.67945 -0.305054)
			(end 0.12065 -0.305054)
			(stroke
				(width 0.1)
				(type default)
			)
			(layer "B.Fab")
		)
		(pad "1" smd circle
			(at 0.40005 0 90)
			(size 0 0)
			(layers "B.Cu" "B.Mask" "B.Paste")
			(net "PVCCD_HV_CPU1")
		)
		(pad "2" smd circle
			(at -0.40005 0 90)
			(size 0 0)
			(layers "B.Cu" "B.Mask" "B.Paste")
			(net "RST_M_GH_CPU1_FPGA_N")
		)
	)
	(footprint ""
		(layer "B.Cu")
		(at 391.416032 -337.85048)
		(property "Reference" "C1397"
			(at 0 0 0)
			(layer "B.SilkS")
			(hide yes)
			(effects
				(font
					(size 1.27 1.27)
				)
				(justify mirror)
			)
		)
		(property "Value" ""
			(at 0 0 0)
			(layer "B.Fab")
			(effects
				(font
					(size 1.27 1.27)
				)
				(justify mirror)
			)
		)
		(duplicate_pad_numbers_are_jumpers no)
		(fp_line
			(start -1.524 -0.762)
			(end -1.524 0.762)
			(stroke
				(width 0.1524)
				(type default)
			)
			(layer "B.SilkS")
		)
		(fp_line
			(start -1.524 0.762)
			(end 1.524 0.762)
			(stroke
				(width 0.1524)
				(type default)
			)
			(layer "B.SilkS")
		)
		(fp_line
			(start 1.524 -0.762)
			(end -1.524 -0.762)
			(stroke
				(width 0.1524)
				(type default)
			)
			(layer "B.SilkS")
		)
		(fp_line
			(start 1.524 0.762)
			(end 1.524 -0.762)
			(stroke
				(width 0.1524)
				(type default)
			)
			(layer "B.SilkS")
		)
		(fp_line
			(start -1.1049 -0.724916)
			(end 1.1049 -0.724916)
			(stroke
				(width 0.1)
				(type default)
			)
			(layer "B.Fab")
		)
		(fp_line
			(start -1.1049 0.724916)
			(end -1.1049 -0.724916)
			(stroke
				(width 0.1)
				(type default)
			)
			(layer "B.Fab")
		)
		(fp_line
			(start 1.1049 -0.724916)
			(end 1.1049 0.724916)
			(stroke
				(width 0.1)
				(type default)
			)
			(layer "B.Fab")
		)
		(fp_line
			(start 1.1049 0.724916)
			(end -1.1049 0.724916)
			(stroke
				(width 0.1)
				(type default)
			)
			(layer "B.Fab")
		)
		(pad "1" smd rect
			(at 0.889 0)
			(size 1.016 1.27)
			(layers "B.Cu" "B.Mask" "B.Paste")
			(net "PVPP_HBM_CPU0")
		)
		(pad "2" smd rect
			(at -0.889 0)
			(size 1.016 1.27)
			(layers "B.Cu" "B.Mask" "B.Paste")
			(net "GND")
		)
	)
)
